(kicad_pcb
	(version 20260206)
	(generator "pcbnew")
	(generator_version "10.0")
	(general
		(thickness 1.6)
		(legacy_teardrops no)
	)
	(paper "A4")
	(title_block
		(title "Bryce Canyon_IOM_M2_16342-2_OCP.brd")
		(comment 1 "Bryce Canyon / footprints 991-997 of 1146")
	)
	(layers
		(0 "F.Cu" signal "TOP")
		(4 "In1.Cu" signal "L2GND")
		(6 "In2.Cu" signal "L3")
		(8 "In3.Cu" signal "L4VCC")
		(10 "In4.Cu" signal "L5VCC")
		(12 "In5.Cu" signal "L6")
		(14 "In6.Cu" signal "L7GND")
		(2 "B.Cu" signal "BOTTOM")
		(9 "F.Adhes" user "F.Adhesive")
		(11 "B.Adhes" user "B.Adhesive")
		(13 "F.Paste" user "Package Geometry/Pastemask Top")
		(15 "B.Paste" user "Package Geometry/Pastemask Bottom")
		(5 "F.SilkS" user "Ref Des/Silkscreen Top")
		(7 "B.SilkS" user "Ref Des/Silkscreen Bottom")
		(1 "F.Mask" user "Board Geometry/Soldermask Top")
		(3 "B.Mask" user "Board Geometry/Soldermask Bottom")
		(17 "Dwgs.User" user "User.Drawings")
		(19 "Cmts.User" user "User.Comments")
		(21 "Eco1.User" user "User.Eco1")
		(23 "Eco2.User" user "User.Eco2")
		(25 "Edge.Cuts" user "Board Geometry/Outline")
		(27 "Margin" user)
		(31 "F.CrtYd" user "Package Geometry/Place Bound Top")
		(29 "B.CrtYd" user "Package Geometry/Place Bound Bottom")
		(35 "F.Fab" user "Ref Des/Assembly Top")
		(33 "B.Fab" user "Ref Des/Assembly Bottom")
	)
	(footprint ""
		(layer "B.Cu")
		(at 61.4934 -148.5138 180)
		(property "Reference" "R389"
			(at 0 0 0)
			(layer "B.SilkS")
			(hide yes)
			(effects
				(font
					(size 1.27 1.27)
				)
				(justify mirror)
			)
		)
		(property "Value" "4K7R2F-GP"
			(at -0.064008 -3.993896 180)
			(unlocked yes)
			(layer "B.Fab")
			(hide yes)
			(effects
				(font
					(size 1.016 1.016)
					(thickness 0.1524)
				)
				(justify mirror)
			)
		)
		(property "Device Type" "R402H16"
			(at -0.064008 -5.517896 180)
			(unlocked yes)
			(layer "B.Fab")
			(hide yes)
			(effects
				(font
					(size 1.016 1.016)
					(thickness 0.1524)
				)
				(justify mirror)
			)
		)
		(duplicate_pad_numbers_are_jumpers no)
		(fp_line
			(start 0.508 -0.9398)
			(end 0.508 0.9398)
			(stroke
				(width 0.1524)
				(type default)
			)
			(layer "B.SilkS")
		)
		(fp_line
			(start -0.508 -0.9398)
			(end 0.508 -0.9398)
			(stroke
				(width 0.1524)
				(type default)
			)
			(layer "B.SilkS")
		)
		(fp_rect
			(start 0.508 0.9398)
			(end -0.508 -0.9398)
			(stroke
				(width 0)
				(type default)
			)
			(fill no)
			(layer "B.CrtYd")
		)
		(fp_rect
			(start 0.508 0.9398)
			(end -0.508 -0.9398)
			(stroke
				(width 0)
				(type default)
			)
			(fill no)
			(layer "B.Fab")
		)
		(pad "1" smd custom
			(at 0 -0.4445)
			(size 0.1397 0.1397)
			(layers "B.Cu" "B.Mask" "B.Paste")
			(net "GND")
			(options
				(clearance outline)
				(anchor circle)
			)
			(primitives
				(gr_poly
					(pts
						(arc
							(start -0.1778 0.2794)
							(mid -0.249642 0.249642)
							(end -0.2794 0.1778)
						)
						(arc
							(start -0.2794 -0.1778)
							(mid -0.249642 -0.249642)
							(end -0.1778 -0.2794)
						)
						(arc
							(start 0.1778 -0.2794)
							(mid 0.249642 -0.249642)
							(end 0.2794 -0.1778)
						)
						(arc
							(start 0.2794 0.1778)
							(mid 0.249642 0.249642)
							(end 0.1778 0.2794)
						)
					)
					(width 0)
					(fill yes)
				)
			)
		)
		(pad "2" smd custom
			(at 0 0.4445)
			(size 0.1397 0.1397)
			(layers "B.Cu" "B.Mask" "B.Paste")
			(net "MAC1_TXD3")
			(options
				(clearance outline)
				(anchor circle)
			)
			(primitives
				(gr_poly
					(pts
						(arc
							(start -0.1778 0.2794)
							(mid -0.249642 0.249642)
							(end -0.2794 0.1778)
						)
						(arc
							(start -0.2794 -0.1778)
							(mid -0.249642 -0.249642)
							(end -0.1778 -0.2794)
						)
						(arc
							(start 0.1778 -0.2794)
							(mid 0.249642 -0.249642)
							(end 0.2794 -0.1778)
						)
						(arc
							(start 0.2794 0.1778)
							(mid 0.249642 0.249642)
							(end 0.1778 0.2794)
						)
					)
					(width 0)
					(fill yes)
				)
			)
		)
	)
	(footprint ""
		(layer "B.Cu")
		(at 10.20699 -141.008862 90)
		(property "Reference" "R254"
			(at 0 0 90)
			(layer "B.SilkS")
			(hide yes)
			(effects
				(font
					(size 1.27 1.27)
				)
				(justify mirror)
			)
		)
		(property "Value" "120R2F-GP"
			(at -0.064008 -3.993896 90)
			(unlocked yes)
			(layer "B.Fab")
			(hide yes)
			(effects
				(font
					(size 1.016 1.016)
					(thickness 0.1524)
				)
				(justify mirror)
			)
		)
		(property "Device Type" "R402H16"
			(at -0.064008 -5.517896 90)
			(unlocked yes)
			(layer "B.Fab")
			(hide yes)
			(effects
				(font
					(size 1.016 1.016)
					(thickness 0.1524)
				)
				(justify mirror)
			)
		)
		(duplicate_pad_numbers_are_jumpers no)
		(fp_line
			(start 0.508 -0.9398)
			(end 0.508 0.9398)
			(stroke
				(width 0.1524)
				(type default)
			)
			(layer "B.SilkS")
		)
		(fp_line
			(start -0.508 -0.9398)
			(end 0.508 -0.9398)
			(stroke
				(width 0.1524)
				(type default)
			)
			(layer "B.SilkS")
		)
		(fp_rect
			(start 0.508 0.9398)
			(end -0.508 -0.9398)
			(stroke
				(width 0)
				(type default)
			)
			(fill no)
			(layer "B.CrtYd")
		)
		(fp_rect
			(start 0.508 0.9398)
			(end -0.508 -0.9398)
			(stroke
				(width 0)
				(type default)
			)
			(fill no)
			(layer "B.Fab")
		)
		(pad "1" smd custom
			(at 0 -0.4445 270)
			(size 0.1397 0.1397)
			(layers "B.Cu" "B.Mask" "B.Paste")
			(net "GND")
			(options
				(clearance outline)
				(anchor circle)
			)
			(primitives
				(gr_poly
					(pts
						(arc
							(start -0.1778 0.2794)
							(mid -0.249642 0.249642)
							(end -0.2794 0.1778)
						)
						(arc
							(start -0.2794 -0.1778)
							(mid -0.249642 -0.249642)
							(end -0.1778 -0.2794)
						)
						(arc
							(start 0.1778 -0.2794)
							(mid 0.249642 -0.249642)
							(end 0.2794 -0.1778)
						)
						(arc
							(start 0.2794 0.1778)
							(mid 0.249642 0.249642)
							(end 0.1778 0.2794)
						)
					)
					(width 0)
					(fill yes)
				)
			)
		)
		(pad "2" smd custom
			(at 0 0.4445 270)
			(size 0.1397 0.1397)
			(layers "B.Cu" "B.Mask" "B.Paste")
			(net "MEMA_10")
			(options
				(clearance outline)
				(anchor circle)
			)
			(primitives
				(gr_poly
					(pts
						(arc
							(start -0.1778 0.2794)
							(mid -0.249642 0.249642)
							(end -0.2794 0.1778)
						)
						(arc
							(start -0.2794 -0.1778)
							(mid -0.249642 -0.249642)
							(end -0.1778 -0.2794)
						)
						(arc
							(start 0.1778 -0.2794)
							(mid 0.249642 -0.249642)
							(end 0.2794 -0.1778)
						)
						(arc
							(start 0.2794 0.1778)
							(mid 0.249642 0.249642)
							(end 0.1778 0.2794)
						)
					)
					(width 0)
					(fill yes)
				)
			)
		)
	)
	(footprint ""
		(layer "B.Cu")
		(at 13.323824 -145.23593 90)
		(property "Reference" "R209"
			(at 0 0 90)
			(layer "B.SilkS")
			(hide yes)
			(effects
				(font
					(size 1.27 1.27)
				)
				(justify mirror)
			)
		)
		(property "Value" "120R2F-GP"
			(at -0.064008 -3.993896 90)
			(unlocked yes)
			(layer "B.Fab")
			(hide yes)
			(effects
				(font
					(size 1.016 1.016)
					(thickness 0.1524)
				)
				(justify mirror)
			)
		)
		(property "Device Type" "R402H16"
			(at -0.064008 -5.517896 90)
			(unlocked yes)
			(layer "B.Fab")
			(hide yes)
			(effects
				(font
					(size 1.016 1.016)
					(thickness 0.1524)
				)
				(justify mirror)
			)
		)
		(duplicate_pad_numbers_are_jumpers no)
		(fp_line
			(start 0.508 -0.9398)
			(end 0.508 0.9398)
			(stroke
				(width 0.1524)
				(type default)
			)
			(layer "B.SilkS")
		)
		(fp_line
			(start -0.508 -0.9398)
			(end 0.508 -0.9398)
			(stroke
				(width 0.1524)
				(type default)
			)
			(layer "B.SilkS")
		)
		(fp_rect
			(start 0.508 0.9398)
			(end -0.508 -0.9398)
			(stroke
				(width 0)
				(type default)
			)
			(fill no)
			(layer "B.CrtYd")
		)
		(fp_rect
			(start 0.508 0.9398)
			(end -0.508 -0.9398)
			(stroke
				(width 0)
				(type default)
			)
			(fill no)
			(layer "B.Fab")
		)
		(pad "1" smd custom
			(at 0 -0.4445 270)
			(size 0.1397 0.1397)
			(layers "B.Cu" "B.Mask" "B.Paste")
			(net "GND")
			(options
				(clearance outline)
				(anchor circle)
			)
			(primitives
				(gr_poly
					(pts
						(arc
							(start -0.1778 0.2794)
							(mid -0.249642 0.249642)
							(end -0.2794 0.1778)
						)
						(arc
							(start -0.2794 -0.1778)
							(mid -0.249642 -0.249642)
							(end -0.1778 -0.2794)
						)
						(arc
							(start 0.1778 -0.2794)
							(mid 0.249642 -0.249642)
							(end 0.2794 -0.1778)
						)
						(arc
							(start 0.2794 0.1778)
							(mid 0.249642 0.249642)
							(end 0.1778 0.2794)
						)
					)
					(width 0)
					(fill yes)
				)
			)
		)
		(pad "2" smd custom
			(at 0 0.4445 270)
			(size 0.1397 0.1397)
			(layers "B.Cu" "B.Mask" "B.Paste")
			(net "MEMCKE")
			(options
				(clearance outline)
				(anchor circle)
			)
			(primitives
				(gr_poly
					(pts
						(arc
							(start -0.1778 0.2794)
							(mid -0.249642 0.249642)
							(end -0.2794 0.1778)
						)
						(arc
							(start -0.2794 -0.1778)
							(mid -0.249642 -0.249642)
							(end -0.1778 -0.2794)
						)
						(arc
							(start 0.1778 -0.2794)
							(mid 0.249642 -0.249642)
							(end 0.2794 -0.1778)
						)
						(arc
							(start 0.2794 0.1778)
							(mid 0.249642 0.249642)
							(end 0.1778 0.2794)
						)
					)
					(width 0)
					(fill yes)
				)
			)
		)
	)
	(footprint ""
		(layer "B.Cu")
		(at 72.780144 -151.998426 -90)
		(property "Reference" "C41"
			(at 0 0 90)
			(layer "B.SilkS")
			(hide yes)
			(effects
				(font
					(size 1.27 1.27)
				)
				(justify mirror)
			)
		)
		(property "Value" "SCD1U16V2KX-3GP"
			(at -1.1811 -2.7051 270)
			(unlocked yes)
			(layer "B.Fab")
			(hide yes)
			(effects
				(font
					(size 1.016 1.016)
					(thickness 0.1524)
				)
				(justify mirror)
			)
		)
		(property "Device Type" "C402H22"
			(at -1.1811 -4.2291 270)
			(unlocked yes)
			(layer "B.Fab")
			(hide yes)
			(effects
				(font
					(size 1.016 1.016)
					(thickness 0.1524)
				)
				(justify mirror)
			)
		)
		(duplicate_pad_numbers_are_jumpers no)
		(fp_rect
			(start 0.4318 0.9525)
			(end -0.4318 -0.9525)
			(stroke
				(width 0)
				(type default)
			)
			(fill no)
			(layer "B.CrtYd")
		)
		(fp_rect
			(start 0.4318 0.9525)
			(end -0.4318 -0.9525)
			(stroke
				(width 0)
				(type default)
			)
			(fill no)
			(layer "B.Fab")
		)
		(pad "1" smd custom
			(at 0 -0.4445 90)
			(size 0.1524 0.1524)
			(layers "B.Cu" "B.Mask" "B.Paste")
			(net "P3V3_STBY")
			(options
				(clearance outline)
				(anchor circle)
			)
			(primitives
				(gr_poly
					(pts
						(arc
							(start 0.3048 0.2032)
							(mid 0.275042 0.275042)
							(end 0.2032 0.3048)
						)
						(arc
							(start -0.2032 0.3048)
							(mid -0.275042 0.275042)
							(end -0.3048 0.2032)
						)
						(arc
							(start -0.3048 -0.2032)
							(mid -0.275042 -0.275042)
							(end -0.2032 -0.3048)
						)
						(arc
							(start 0.2032 -0.3048)
							(mid 0.275042 -0.275042)
							(end 0.3048 -0.2032)
						)
					)
					(width 0)
					(fill yes)
				)
			)
		)
		(pad "2" smd custom
			(at 0 0.4445 90)
			(size 0.1524 0.1524)
			(layers "B.Cu" "B.Mask" "B.Paste")
			(net "GND")
			(options
				(clearance outline)
				(anchor circle)
			)
			(primitives
				(gr_poly
					(pts
						(arc
							(start 0.3048 0.2032)
							(mid 0.275042 0.275042)
							(end 0.2032 0.3048)
						)
						(arc
							(start -0.2032 0.3048)
							(mid -0.275042 0.275042)
							(end -0.3048 0.2032)
						)
						(arc
							(start -0.3048 -0.2032)
							(mid -0.275042 -0.275042)
							(end -0.2032 -0.3048)
						)
						(arc
							(start 0.2032 -0.3048)
							(mid 0.275042 -0.275042)
							(end 0.3048 -0.2032)
						)
					)
					(width 0)
					(fill yes)
				)
			)
		)
	)
	(footprint ""
		(layer "B.Cu")
		(at 24.8666 -129.1082 180)
		(property "Reference" "R244"
			(at 0 0 0)
			(layer "B.SilkS")
			(hide yes)
			(effects
				(font
					(size 1.27 1.27)
				)
				(justify mirror)
			)
		)
		(property "Value" "120R2F-GP"
			(at -0.064008 -3.993896 180)
			(unlocked yes)
			(layer "B.Fab")
			(hide yes)
			(effects
				(font
					(size 1.016 1.016)
					(thickness 0.1524)
				)
				(justify mirror)
			)
		)
		(property "Device Type" "R402H16"
			(at -0.064008 -5.517896 180)
			(unlocked yes)
			(layer "B.Fab")
			(hide yes)
			(effects
				(font
					(size 1.016 1.016)
					(thickness 0.1524)
				)
				(justify mirror)
			)
		)
		(duplicate_pad_numbers_are_jumpers no)
		(fp_line
			(start 0.508 -0.9398)
			(end 0.508 0.9398)
			(stroke
				(width 0.1524)
				(type default)
			)
			(layer "B.SilkS")
		)
		(fp_line
			(start -0.508 -0.9398)
			(end 0.508 -0.9398)
			(stroke
				(width 0.1524)
				(type default)
			)
			(layer "B.SilkS")
		)
		(fp_rect
			(start 0.508 0.9398)
			(end -0.508 -0.9398)
			(stroke
				(width 0)
				(type default)
			)
			(fill no)
			(layer "B.CrtYd")
		)
		(fp_rect
			(start 0.508 0.9398)
			(end -0.508 -0.9398)
			(stroke
				(width 0)
				(type default)
			)
			(fill no)
			(layer "B.Fab")
		)
		(pad "1" smd custom
			(at 0 -0.4445)
			(size 0.1397 0.1397)
			(layers "B.Cu" "B.Mask" "B.Paste")
			(net "GND")
			(options
				(clearance outline)
				(anchor circle)
			)
			(primitives
				(gr_poly
					(pts
						(arc
							(start -0.1778 0.2794)
							(mid -0.249642 0.249642)
							(end -0.2794 0.1778)
						)
						(arc
							(start -0.2794 -0.1778)
							(mid -0.249642 -0.249642)
							(end -0.1778 -0.2794)
						)
						(arc
							(start 0.1778 -0.2794)
							(mid 0.249642 -0.249642)
							(end 0.2794 -0.1778)
						)
						(arc
							(start 0.2794 0.1778)
							(mid 0.249642 0.249642)
							(end 0.1778 0.2794)
						)
					)
					(width 0)
					(fill yes)
				)
			)
		)
		(pad "2" smd custom
			(at 0 0.4445)
			(size 0.1397 0.1397)
			(layers "B.Cu" "B.Mask" "B.Paste")
			(net "MEMA_5")
			(options
				(clearance outline)
				(anchor circle)
			)
			(primitives
				(gr_poly
					(pts
						(arc
							(start -0.1778 0.2794)
							(mid -0.249642 0.249642)
							(end -0.2794 0.1778)
						)
						(arc
							(start -0.2794 -0.1778)
							(mid -0.249642 -0.249642)
							(end -0.1778 -0.2794)
						)
						(arc
							(start 0.1778 -0.2794)
							(mid 0.249642 -0.249642)
							(end 0.2794 -0.1778)
						)
						(arc
							(start 0.2794 0.1778)
							(mid 0.249642 0.249642)
							(end 0.1778 0.2794)
						)
					)
					(width 0)
					(fill yes)
				)
			)
		)
	)
	(footprint ""
		(layer "B.Cu")
		(at 170.035728 -125.527308 -90)
		(property "Reference" "C620"
			(at 0 0 90)
			(layer "B.SilkS")
			(hide yes)
			(effects
				(font
					(size 1.27 1.27)
				)
				(justify mirror)
			)
		)
		(property "Value" "SCD1U16V2KX-3GP"
			(at -1.1811 -2.7051 270)
			(unlocked yes)
			(layer "B.Fab")
			(hide yes)
			(effects
				(font
					(size 1.016 1.016)
					(thickness 0.1524)
				)
				(justify mirror)
			)
		)
		(property "Device Type" "C402H22"
			(at -1.1811 -4.2291 270)
			(unlocked yes)
			(layer "B.Fab")
			(hide yes)
			(effects
				(font
					(size 1.016 1.016)
					(thickness 0.1524)
				)
				(justify mirror)
			)
		)
		(duplicate_pad_numbers_are_jumpers no)
		(fp_rect
			(start 0.4318 0.9525)
			(end -0.4318 -0.9525)
			(stroke
				(width 0)
				(type default)
			)
			(fill no)
			(layer "B.CrtYd")
		)
		(fp_rect
			(start 0.4318 0.9525)
			(end -0.4318 -0.9525)
			(stroke
				(width 0)
				(type default)
			)
			(fill no)
			(layer "B.Fab")
		)
		(pad "1" smd custom
			(at 0 -0.4445 90)
			(size 0.1524 0.1524)
			(layers "B.Cu" "B.Mask" "B.Paste")
			(net "P3V3_M2")
			(options
				(clearance outline)
				(anchor circle)
			)
			(primitives
				(gr_poly
					(pts
						(arc
							(start 0.3048 0.2032)
							(mid 0.275042 0.275042)
							(end 0.2032 0.3048)
						)
						(arc
							(start -0.2032 0.3048)
							(mid -0.275042 0.275042)
							(end -0.3048 0.2032)
						)
						(arc
							(start -0.3048 -0.2032)
							(mid -0.275042 -0.275042)
							(end -0.2032 -0.3048)
						)
						(arc
							(start 0.2032 -0.3048)
							(mid 0.275042 -0.275042)
							(end 0.3048 -0.2032)
						)
					)
					(width 0)
					(fill yes)
				)
			)
		)
		(pad "2" smd custom
			(at 0 0.4445 90)
			(size 0.1524 0.1524)
			(layers "B.Cu" "B.Mask" "B.Paste")
			(net "GND")
			(options
				(clearance outline)
				(anchor circle)
			)
			(primitives
				(gr_poly
					(pts
						(arc
							(start 0.3048 0.2032)
							(mid 0.275042 0.275042)
							(end 0.2032 0.3048)
						)
						(arc
							(start -0.2032 0.3048)
							(mid -0.275042 0.275042)
							(end -0.3048 0.2032)
						)
						(arc
							(start -0.3048 -0.2032)
							(mid -0.275042 -0.275042)
							(end -0.2032 -0.3048)
						)
						(arc
							(start 0.2032 -0.3048)
							(mid 0.275042 -0.275042)
							(end 0.3048 -0.2032)
						)
					)
					(width 0)
					(fill yes)
				)
			)
		)
	)
	(footprint ""
		(layer "B.Cu")
		(at 37.2364 -131.826 180)
		(property "Reference" "R416"
			(at 0 0 0)
			(layer "B.SilkS")
			(hide yes)
			(effects
				(font
					(size 1.27 1.27)
				)
				(justify mirror)
			)
		)
		(property "Value" "4K7R2F-GP"
			(at -0.064008 -3.993896 180)
			(unlocked yes)
			(layer "B.Fab")
			(hide yes)
			(effects
				(font
					(size 1.016 1.016)
					(thickness 0.1524)
				)
				(justify mirror)
			)
		)
		(property "Device Type" "R402H16"
			(at -0.064008 -5.517896 180)
			(unlocked yes)
			(layer "B.Fab")
			(hide yes)
			(effects
				(font
					(size 1.016 1.016)
					(thickness 0.1524)
				)
				(justify mirror)
			)
		)
		(duplicate_pad_numbers_are_jumpers no)
		(fp_line
			(start 0.508 -0.9398)
			(end 0.508 0.9398)
			(stroke
				(width 0.1524)
				(type default)
			)
			(layer "B.SilkS")
		)
		(fp_line
			(start -0.508 -0.9398)
			(end 0.508 -0.9398)
			(stroke
				(width 0.1524)
				(type default)
			)
			(layer "B.SilkS")
		)
		(fp_rect
			(start 0.508 0.9398)
			(end -0.508 -0.9398)
			(stroke
				(width 0)
				(type default)
			)
			(fill no)
			(layer "B.CrtYd")
		)
		(fp_rect
			(start 0.508 0.9398)
			(end -0.508 -0.9398)
			(stroke
				(width 0)
				(type default)
			)
			(fill no)
			(layer "B.Fab")
		)
		(pad "1" smd custom
			(at 0 -0.4445)
			(size 0.1397 0.1397)
			(layers "B.Cu" "B.Mask" "B.Paste")
			(net "P3V3_STBY")
			(options
				(clearance outline)
				(anchor circle)
			)
			(primitives
				(gr_poly
					(pts
						(arc
							(start -0.1778 0.2794)
							(mid -0.249642 0.249642)
							(end -0.2794 0.1778)
						)
						(arc
							(start -0.2794 -0.1778)
							(mid -0.249642 -0.249642)
							(end -0.1778 -0.2794)
						)
						(arc
							(start 0.1778 -0.2794)
							(mid 0.249642 -0.249642)
							(end 0.2794 -0.1778)
						)
						(arc
							(start 0.2794 0.1778)
							(mid 0.249642 0.249642)
							(end 0.1778 0.2794)
						)
					)
					(width 0)
					(fill yes)
				)
			)
		)
		(pad "2" smd custom
			(at 0 0.4445)
			(size 0.1397 0.1397)
			(layers "B.Cu" "B.Mask" "B.Paste")
			(net "BMC_ML_PWR_YELLOW_LED")
			(options
				(clearance outline)
				(anchor circle)
			)
			(primitives
				(gr_poly
					(pts
						(arc
							(start -0.1778 0.2794)
							(mid -0.249642 0.249642)
							(end -0.2794 0.1778)
						)
						(arc
							(start -0.2794 -0.1778)
							(mid -0.249642 -0.249642)
							(end -0.1778 -0.2794)
						)
						(arc
							(start 0.1778 -0.2794)
							(mid 0.249642 -0.249642)
							(end 0.2794 -0.1778)
						)
						(arc
							(start 0.2794 0.1778)
							(mid 0.249642 0.249642)
							(end 0.1778 0.2794)
						)
					)
					(width 0)
					(fill yes)
				)
			)
		)
	)
)
